# T6G (Grand Teton) — schematic netlist excerpt (pin names and nets, part order shuffled) for the footprints in the layout excerpt that follows; sources: Cadence DE-HDL packaged netlist, KiCad conversion of 04192023_DAF0TMB3IC0_F0TG_MB_C_brd_V02_OCP.brd

PC272  Q_CAPP  270UF 16V 20% OSCON  pkg THLF  page 211 : A = SW_P12V_AUX_PVDDCR_CPU0_P1_FLT ; B = GND
C869  Q_CAP_DIFFBUS  DIFF BUS_0.22UF 6.3V 20% X6S  pkg C0201  page 64 : \1\ = P5E_CPU0_P2_TX_C_DP<0> ; \2\ = P5E_CPU0_P2_TX_DP<0>
R132  Q_RES  0 5% CHIP  pkg 0402LF  page 82 : A = FM_APML_MUX2_OE_N ; B = FM_APML_MUX2_OE_R_N
C847  Q_CAP_DIFFBUS  DIFF BUS_0.22UF 6.3V 20% X6S  pkg C0201  page 64 : \1\ = P5E_CPU0_P2_TX_C_DP<11> ; \2\ = P5E_CPU0_P2_TX_DP<11>

(kicad_pcb
	(version 20260206)
	(generator "pcbnew")
	(generator_version "10.0")
	(general
		(thickness 1.6)
		(legacy_teardrops no)
	)
	(paper "A4")
	(title_block
		(title "04192023_DAF0TMB3IC0_F0TG_MB_C_brd_V02_OCP.brd")
		(comment 1 "Grand Teton / footprints 3158-3161 of 8354")
	)
	(layers
		(0 "F.Cu" signal "TOP")
		(4 "In1.Cu" signal "GND")
		(6 "In2.Cu" signal "IN1")
		(8 "In3.Cu" signal "GND1")
		(10 "In4.Cu" signal "IN2")
		(12 "In5.Cu" signal "GND2")
		(14 "In6.Cu" signal "IN3")
		(16 "In7.Cu" signal "GND3")
		(18 "In8.Cu" signal "VCC")
		(20 "In9.Cu" signal "VCC1")
		(22 "In10.Cu" signal "GND4")
		(24 "In11.Cu" signal "IN4")
		(26 "In12.Cu" signal "GND5")
		(28 "In13.Cu" signal "IN5")
		(30 "In14.Cu" signal "GND6")
		(32 "In15.Cu" signal "IN6")
		(34 "In16.Cu" signal "GND7")
		(2 "B.Cu" signal "BOTTOM")
		(9 "F.Adhes" user "F.Adhesive")
		(11 "B.Adhes" user "B.Adhesive")
		(13 "F.Paste" user "Package Geometry/Pastemask Top")
		(15 "B.Paste" user "Package Geometry/Pastemask Bottom")
		(5 "F.SilkS" user "Ref Des/Silkscreen Top")
		(7 "B.SilkS" user "Ref Des/Silkscreen Bottom")
		(1 "F.Mask" user "Board Geometry/Soldermask Top")
		(3 "B.Mask" user "Board Geometry/Soldermask Bottom")
		(17 "Dwgs.User" user "User.Drawings")
		(19 "Cmts.User" user "User.Comments")
		(21 "Eco1.User" user "User.Eco1")
		(23 "Eco2.User" user "User.Eco2")
		(25 "Edge.Cuts" user "Board Geometry/Outline")
		(27 "Margin" user)
		(31 "F.CrtYd" user "Package Geometry/Place Bound Top")
		(29 "B.CrtYd" user "Package Geometry/Place Bound Bottom")
		(35 "F.Fab" user "Ref Des/Assembly Top")
		(33 "B.Fab" user "Ref Des/Assembly Bottom")
	)
	(footprint ""
		(layer "F.Cu")
		(at 82.989674 -165.962076 180)
		(property "Reference" "PC272"
			(at 2.327148 -2.902204 0)
			(unlocked yes)
			(layer "F.SilkS")
			(effects
				(font
					(size 0.7874 0.5842)
					(thickness 0.1524)
				)
				(justify left)
			)
		)
		(property "Value" ""
			(at 0 0 180)
			(layer "F.Fab")
			(effects
				(font
					(size 1.27 1.27)
				)
			)
		)
		(duplicate_pad_numbers_are_jumpers no)
		(fp_line
			(start -3.400044 1.249934)
			(end 3.400044 1.249934)
			(stroke
				(width 0.1524)
				(type default)
			)
			(layer "F.SilkS")
		)
		(fp_circle
			(center 0 1.249934)
			(end -3.400044 1.249934)
			(stroke
				(width 0.1524)
				(type default)
			)
			(fill no)
			(layer "F.SilkS")
		)
		(fp_poly
			(pts
				(arc
					(start 3.400044 1.249934)
					(mid 0 4.649978)
					(end -3.400044 1.249934)
				)
			)
			(stroke
				(width 0)
				(type default)
			)
			(fill yes)
			(layer "F.SilkS")
		)
		(fp_circle
			(center 0 1.249934)
			(end -3.400044 1.249934)
			(stroke
				(width 0.1)
				(type default)
			)
			(fill no)
			(layer "F.Fab")
		)
		(pad "1" thru_hole rect
			(at 0 0 180)
			(size 1.524 1.524)
			(drill 1.016)
			(layers "*.Cu" "*.Mask")
			(remove_unused_layers no)
			(net "SW_P12V_AUX_PVDDCR_CPU0_P1_FLT")
			(clearance 0)
			(padstack
				(mode front_inner_back)
				(layer "Inner"
					(shape circle)
					(size 1.524 1.524)
					(clearance 0)
				)
				(layer "B.Cu"
					(shape rect)
					(size 1.524 1.524)
					(clearance 0)
				)
			)
		)
		(pad "2" thru_hole circle
			(at 0 2.500122 180)
			(size 1.524 1.524)
			(drill 1.016)
			(layers "*.Cu" "*.Mask")
			(remove_unused_layers no)
			(net "GND")
			(clearance 0)
		)
	)
	(footprint ""
		(layer "F.Cu")
		(at 398.595088 -390.77646 180)
		(property "Reference" "C869"
			(at 0 0 180)
			(layer "F.SilkS")
			(hide yes)
			(effects
				(font
					(size 1.27 1.27)
				)
			)
		)
		(property "Value" ""
			(at 0 0 180)
			(layer "F.Fab")
			(effects
				(font
					(size 1.27 1.27)
				)
			)
		)
		(duplicate_pad_numbers_are_jumpers no)
		(fp_line
			(start 0.299974 0.150114)
			(end -0.299974 0.150114)
			(stroke
				(width 0.1)
				(type default)
			)
			(layer "F.Fab")
		)
		(fp_line
			(start 0.299974 -0.150114)
			(end 0.299974 0.150114)
			(stroke
				(width 0.1)
				(type default)
			)
			(layer "F.Fab")
		)
		(fp_line
			(start -0.299974 0.150114)
			(end -0.299974 -0.150114)
			(stroke
				(width 0.1)
				(type default)
			)
			(layer "F.Fab")
		)
		(fp_line
			(start -0.299974 -0.150114)
			(end 0.299974 -0.150114)
			(stroke
				(width 0.1)
				(type default)
			)
			(layer "F.Fab")
		)
		(pad "1" smd rect
			(at -0.2667 0 180)
			(size 0.3048 0.381)
			(layers "F.Cu" "F.Mask" "F.Paste")
			(net "P5E_CPU0_P2_TX_C_DP<0>")
		)
		(pad "2" smd rect
			(at 0.2667 0 180)
			(size 0.3048 0.381)
			(layers "F.Cu" "F.Mask" "F.Paste")
			(net "P5E_CPU0_P2_TX_DP<0>")
		)
	)
	(footprint ""
		(layer "F.Cu")
		(at 419.03904 -381.41783 -90)
		(property "Reference" "C847"
			(at 0 0 270)
			(layer "F.SilkS")
			(hide yes)
			(effects
				(font
					(size 1.27 1.27)
				)
			)
		)
		(property "Value" ""
			(at 0 0 270)
			(layer "F.Fab")
			(effects
				(font
					(size 1.27 1.27)
				)
			)
		)
		(duplicate_pad_numbers_are_jumpers no)
		(fp_line
			(start -0.299974 0.150114)
			(end -0.299974 -0.150114)
			(stroke
				(width 0.1)
				(type default)
			)
			(layer "F.Fab")
		)
		(fp_line
			(start 0.299974 0.150114)
			(end -0.299974 0.150114)
			(stroke
				(width 0.1)
				(type default)
			)
			(layer "F.Fab")
		)
		(fp_line
			(start -0.299974 -0.150114)
			(end 0.299974 -0.150114)
			(stroke
				(width 0.1)
				(type default)
			)
			(layer "F.Fab")
		)
		(fp_line
			(start 0.299974 -0.150114)
			(end 0.299974 0.150114)
			(stroke
				(width 0.1)
				(type default)
			)
			(layer "F.Fab")
		)
		(pad "1" smd rect
			(at -0.2667 0 270)
			(size 0.3048 0.381)
			(layers "F.Cu" "F.Mask" "F.Paste")
			(net "P5E_CPU0_P2_TX_C_DP<11>")
		)
		(pad "2" smd rect
			(at 0.2667 0 270)
			(size 0.3048 0.381)
			(layers "F.Cu" "F.Mask" "F.Paste")
			(net "P5E_CPU0_P2_TX_DP<11>")
		)
	)
	(footprint ""
		(layer "F.Cu")
		(at 212.993732 -112.662208 180)
		(property "Reference" "R132"
			(at 0 0 180)
			(layer "F.SilkS")
			(hide yes)
			(effects
				(font
					(size 1.27 1.27)
				)
			)
		)
		(property "Value" ""
			(at 0 0 180)
			(layer "F.Fab")
			(effects
				(font
					(size 1.27 1.27)
				)
			)
		)
		(duplicate_pad_numbers_are_jumpers no)
		(fp_line
			(start 0.7874 0.4064)
			(end -0.7874 0.4064)
			(stroke
				(width 0.1524)
				(type default)
			)
			(layer "F.SilkS")
		)
		(fp_line
			(start 0.7874 -0.4064)
			(end 0.7874 0.4064)
			(stroke
				(width 0.1524)
				(type default)
			)
			(layer "F.SilkS")
		)
		(fp_line
			(start -0.7874 0.4064)
			(end -0.7874 -0.4064)
			(stroke
				(width 0.1524)
				(type default)
			)
			(layer "F.SilkS")
		)
		(fp_line
			(start -0.7874 -0.4064)
			(end 0.7874 -0.4064)
			(stroke
				(width 0.1524)
				(type default)
			)
			(layer "F.SilkS")
		)
		(fp_line
			(start 0.67945 0.3048)
			(end 0.120396 0.3048)
			(stroke
				(width 0.1)
				(type default)
			)
			(layer "F.Fab")
		)
		(fp_line
			(start 0.67945 -0.3048)
			(end 0.67945 0.3048)
			(stroke
				(width 0.1)
				(type default)
			)
			(layer "F.Fab")
		)
		(fp_line
			(start 0.12065 -0.2794)
			(end 0.12065 -0.3048)
			(stroke
				(width 0.1)
				(type default)
			)
			(layer "F.Fab")
		)
		(fp_line
			(start 0.12065 -0.3048)
			(end 0.67945 -0.3048)
			(stroke
				(width 0.1)
				(type default)
			)
			(layer "F.Fab")
		)
		(fp_line
			(start 0.120396 0.3048)
			(end 0.120396 0.2794)
			(stroke
				(width 0.1)
				(type default)
			)
			(layer "F.Fab")
		)
		(fp_line
			(start 0.120396 0.2794)
			(end -0.12065 0.2794)
			(stroke
				(width 0.1)
				(type default)
			)
			(layer "F.Fab")
		)
		(fp_line
			(start -0.12065 0.3048)
			(end -0.67945 0.3048)
			(stroke
				(width 0.1)
				(type default)
			)
			(layer "F.Fab")
		)
		(fp_line
			(start -0.12065 0.2794)
			(end -0.12065 0.3048)
			(stroke
				(width 0.1)
				(type default)
			)
			(layer "F.Fab")
		)
		(fp_line
			(start -0.12065 -0.2794)
			(end 0.12065 -0.2794)
			(stroke
				(width 0.1)
				(type default)
			)
			(layer "F.Fab")
		)
		(fp_line
			(start -0.12065 -0.305054)
			(end -0.12065 -0.2794)
			(stroke
				(width 0.1)
				(type default)
			)
			(layer "F.Fab")
		)
		(fp_line
			(start -0.67945 0.3048)
			(end -0.67945 -0.305054)
			(stroke
				(width 0.1)
				(type default)
			)
			(layer "F.Fab")
		)
		(fp_line
			(start -0.67945 -0.305054)
			(end -0.12065 -0.305054)
			(stroke
				(width 0.1)
				(type default)
			)
			(layer "F.Fab")
		)
		(pad "1" smd circle
			(at -0.40005 0 180)
			(size 0 0)
			(layers "F.Cu" "F.Mask" "F.Paste")
			(net "FM_APML_MUX2_OE_N")
		)
		(pad "2" smd circle
			(at 0.40005 0 180)
			(size 0 0)
			(layers "F.Cu" "F.Mask" "F.Paste")
			(net "FM_APML_MUX2_OE_R_N")
		)
	)
)
